FILE_TYPE = CONNECTIVITY;
{Allegro Design Entry HDL 17.2-2016 S081 (4005846) 1/11/2022}
"PAGE_NUMBER" = 242;
0"NC";
1"P3V3_AUX\g";
2"P3V3_AUX\g";
3"P3V3_AUX\g";
4"P3V3_AUX\g";
5"P3V3_AUX\g";
6"P5V\g";
7"P5V_AUX\g";
8"P3V3_AUX\g";
9"P3V3\g";
10"GND\g";
11"GND\g";
12"GND\g";
13"GND\g";
14"GND\g";
15"GND\g";
16"GND\g";
17"GND\g";
18"GND\g";
19"LED_P5V_AUX";
20"LED_P5V";
21"LED_PWRGD_PS_PWROK_PLD_D";
22"PWRGD_PS_PWROK_PLD";
23"LED_FM_PCH_SLP_S4_N";
24"LED_FM_PCH_SLP_S4_N_D";
25"LED_RST_RSMRST_PLD_R_N_D";
26"LED_PWRGD_P1V05_PCH_AUX_D";
27"PWRGD_P1V05_PCH_AUX";
28"LED_PWRGD_P1V8_PCH_AUX_D";
29"RST_RSMRST_PLD_R_N";
30"PWRGD_P1V8_PCH_AUX";
31"FM_PCH_SLP_S3_N";
32"LED_FM_PCH_SLP_S3_N";
33"FM_PCH_SLP_S4_N";
34"LED_PWRGD_P1V8_PCH_AUX";
35"LED_RST_RSMRST_PLD_R_N";
36"LED_FM_PCH_SLP_S3_N_D";
37"LED_PWRGD_PS_PWROK_PLD";
38"LED_PWRGD_P1V05_PCH_AUX";
39"LED_P3V3";
%"UNIVERSAL_GND"
"1","(-5775,7825)","0","logical_power","I10";
;
HDL_POWER"GND"
CDS_LIB"logical_power";
"A"12;
%"Q_LED"
"1","(-4725,4575)","2","pure_quanta","I11";
;
PART_NUMBER"BEBL0172Z00"
PACK_TYPE"SMLF"
MANUF_PN"LTST-C281TBKT-5A"
MATERIAL"IC"
COLOR"LED_BLUE"
LOCATION"D94"
CDS_LIB"pure_quanta"
NEEDS_NO_SIZE"TRUE"
$SEC"1"
CDS_SEC"1";
"A"
$PN"A"23;
"C"
$PN"C"24;
%"Q_RES"
"1","(-3375,4575)","0","pure_quanta","I12";
;
PART_NUMBER"CS11302FB03"
MATERIAL"CHIP"
VALUE"130"
TOLERANCE"1%"
WATTAGE"1/16W"
PACK_TYPE"0402LF"
$LOCATION"R3073"
CDS_LIB"pure_quanta"
CDS_LOCATION"R3073"
$SEC"1"
CDS_SEC"1";
"B"
$PN"2"8;
"A"
$PN"1"23;
%"Q_LED"
"1","(-4750,5900)","2","pure_quanta","I13";
;
PART_NUMBER"BEBL0172Z00"
MANUF_PN"LTST-C281TBKT-5A"
COLOR"LED_BLUE"
MATERIAL"IC"
PACK_TYPE"SMLF"
LOCATION"D93"
NEEDS_NO_SIZE"TRUE"
CDS_LIB"pure_quanta"
$SEC"1"
CDS_SEC"1";
"A"
$PN"A"35;
"C"
$PN"C"25;
%"Q_RES"
"1","(-3325,5900)","0","pure_quanta","I14";
;
PART_NUMBER"CS11302FB03"
TOLERANCE"1%"
WATTAGE"1/16W"
VALUE"130"
MATERIAL"CHIP"
PACK_TYPE"0402LF"
$LOCATION"R3074"
CDS_LIB"pure_quanta"
CDS_LOCATION"R3074"
$SEC"1"
CDS_SEC"1";
"B"
$PN"2"5;
"A"
$PN"1"35;
%"Q_RES"
"1","(-3375,7125)","0","pure_quanta","I15";
;
PART_NUMBER"CS11302FB03"
PACK_TYPE"0402LF"
TOLERANCE"1%"
VALUE"130"
MATERIAL"CHIP"
WATTAGE"1/16W"
$LOCATION"R3072"
CDS_LIB"pure_quanta"
CDS_LOCATION"R3072"
$SEC"1"
CDS_SEC"1";
"B"
$PN"2"4;
"A"
$PN"1"38;
%"MOSFET_NCH_DUAL"
"1","(-5825,8175)","0","pure_quanta","I17";
;
PART_NUMBER"BAM138K0003"
MATERIAL"IC"
PART_TYPE"SMLF"
VALUE"PJT138K"
LOCATION"Q76"
NEEDS_NO_SIZE"TRUE"
CDS_LMAN_SYM_OUTLINE"-150,150,150,-150"
CDS_LIB"pure_quanta"
$SEC"1"
CDS_SEC"1";
"D1"
$PN"6"28;
"G1"
$PN"2"30;
"S1"
$PN"1"12;
%"Q_LED"
"1","(-4750,8450)","2","pure_quanta","I18";
;
PART_NUMBER"BEBL0172Z00"
MATERIAL"IC"
COLOR"LED_BLUE"
PACK_TYPE"SMLF"
MANUF_PN"LTST-C281TBKT-5A"
LOCATION"D91"
CDS_LIB"pure_quanta"
NEEDS_NO_SIZE"TRUE"
$SEC"1"
CDS_SEC"1";
"A"
$PN"A"34;
"C"
$PN"C"28;
%"Q_RES"
"1","(-3400,8450)","0","pure_quanta","I19";
;
PART_NUMBER"CS11302FB03"
WATTAGE"1/16W"
MATERIAL"CHIP"
VALUE"130"
TOLERANCE"1%"
PACK_TYPE"0402LF"
$LOCATION"R3071"
CDS_LIB"pure_quanta"
CDS_LOCATION"R3071"
$SEC"1"
CDS_SEC"1";
"B"
$PN"2"3;
"A"
$PN"1"34;
%"UNIVERSAL_POWER"
"1","(-2775,4725)","0","logical_power","I20";
;
HDL_POWER"P3V3_AUX"
CDS_LIB"logical_power";
"A"8;
%"UNIVERSAL_POWER"
"1","(-2725,6075)","0","logical_power","I23";
;
HDL_POWER"P3V3_AUX"
CDS_LIB"logical_power";
"A"5;
%"UNIVERSAL_POWER"
"1","(-2775,7250)","0","logical_power","I25";
;
HDL_POWER"P3V3_AUX"
CDS_LIB"logical_power";
"A"4;
%"MOSFET_NCH_DUAL"
"2","(-1050,6850)","0","pure_quanta","I26";
;
PART_NUMBER"BAM138K0003"
MATERIAL"IC"
PART_TYPE"SMLF"
VALUE"PJT138K"
LOCATION"Q78"
SEC_TYPE""
CDS_LIB"pure_quanta"
NEEDS_NO_SIZE"TRUE"
CDS_LMAN_SYM_OUTLINE"-150,150,150,-150"
SEC"2";
"S2"
$PN"4"11;
"G2"
$PN"5"22;
"D2"
$PN"3"21;
%"UNIVERSAL_GND"
"1","(-1000,6500)","0","logical_power","I28";
;
HDL_POWER"GND"
CDS_LIB"logical_power";
"A"11;
%"MOSFET_NCH_DUAL"
"2","(-5825,4300)","0","pure_quanta","I3";
;
PART_NUMBER"BAM138K0003"
PART_TYPE"SMLF"
MATERIAL"IC"
VALUE"PJT138K"
LOCATION"Q77"
SEC_TYPE""
CDS_LIB"pure_quanta"
NEEDS_NO_SIZE"TRUE"
CDS_LMAN_SYM_OUTLINE"-150,150,150,-150"
SEC"2";
"S2"
$PN"4"15;
"G2"
$PN"5"33;
"D2"
$PN"3"24;
%"UNIVERSAL_GND"
"1","(-1000,7825)","0","logical_power","I30";
;
HDL_POWER"GND"
CDS_LIB"logical_power";
"A"10;
%"Q_LED"
"1","(25,7125)","2","pure_quanta","I31";
;
PART_NUMBER"BEBL0172Z00"
MANUF_PN"LTST-C281TBKT-5A"
PACK_TYPE"SMLF"
COLOR"LED_BLUE"
MATERIAL"IC"
LOCATION"D96"
CDS_LIB"pure_quanta"
NEEDS_NO_SIZE"TRUE"
$SEC"1"
CDS_SEC"1";
"A"
$PN"A"37;
"C"
$PN"C"21;
%"UNIVERSAL_POWER"
"1","(-2750,8600)","0","logical_power","I32";
;
HDL_POWER"P3V3_AUX"
CDS_LIB"logical_power";
"A"3;
%"MOSFET_NCH_DUAL"
"1","(-1050,8175)","0","pure_quanta","I34";
;
PART_NUMBER"BAM138K0003"
VALUE"PJT138K"
PART_TYPE"SMLF"
MATERIAL"IC"
LOCATION"Q78"
NEEDS_NO_SIZE"TRUE"
CDS_LMAN_SYM_OUTLINE"-150,150,150,-150"
CDS_LIB"pure_quanta"
$SEC"1"
CDS_SEC"1";
"D1"
$PN"6"36;
"G1"
$PN"2"31;
"S1"
$PN"1"10;
%"Q_LED"
"1","(25,8450)","2","pure_quanta","I35";
;
PART_NUMBER"BEBL0172Z00"
COLOR"LED_BLUE"
MATERIAL"IC"
MANUF_PN"LTST-C281TBKT-5A"
PACK_TYPE"SMLF"
LOCATION"D95"
NEEDS_NO_SIZE"TRUE"
CDS_LIB"pure_quanta"
$SEC"1"
CDS_SEC"1";
"A"
$PN"A"32;
"C"
$PN"C"36;
%"Q_RES"
"1","(1325,7125)","0","pure_quanta","I37";
;
PART_NUMBER"CS11302FB03"
PACK_TYPE"0402LF"
WATTAGE"1/16W"
MATERIAL"CHIP"
TOLERANCE"1%"
VALUE"130"
$LOCATION"R3075"
CDS_LIB"pure_quanta"
CDS_LOCATION"R3075"
$SEC"1"
CDS_SEC"1";
"B"
$PN"2"2;
"A"
$PN"1"37;
%"UNIVERSAL_POWER"
"1","(1975,7275)","0","logical_power","I39";
;
HDL_POWER"P3V3_AUX"
CDS_LIB"logical_power";
"A"2;
%"UNIVERSAL_GND"
"1","(-5775,3950)","0","logical_power","I4";
;
HDL_POWER"GND"
CDS_LIB"logical_power";
"A"15;
%"UNIVERSAL_POWER"
"1","(1950,8625)","0","logical_power","I40";
;
HDL_POWER"P3V3_AUX"
CDS_LIB"logical_power";
"A"1;
%"Q_RES"
"1","(1350,8450)","0","pure_quanta","I41";
;
PART_NUMBER"CS11302FB03"
VALUE"130"
TOLERANCE"1%"
MATERIAL"CHIP"
WATTAGE"1/16W"
PACK_TYPE"0402LF"
$LOCATION"R3078"
CDS_LIB"pure_quanta"
CDS_LOCATION"R3078"
$SEC"1"
CDS_SEC"1";
"B"
$PN"2"1;
"A"
$PN"1"32;
%"Q_LED"
"1","(-4750,7125)","2","pure_quanta","I42";
;
PART_NUMBER"BEBL0172Z00"
MANUF_PN"LTST-C281TBKT-5A"
PACK_TYPE"SMLF"
MATERIAL"IC"
COLOR"LED_BLUE"
LOCATION"D92"
CDS_LIB"pure_quanta"
NEEDS_NO_SIZE"TRUE"
$SEC"1"
CDS_SEC"1";
"A"
$PN"A"38;
"C"
$PN"C"26;
%"UNIVERSAL_GND"
"1","(-1725,5500)","0","logical_power","I49";
;
CDS_LIB"logical_power"
HDL_POWER"GND";
"A"16;
%"UNIVERSAL_GND"
"1","(-5775,5275)","0","logical_power","I5";
;
HDL_POWER"GND"
CDS_LIB"logical_power";
"A"14;
%"UNIVERSAL_POWER"
"1","(375,6000)","0","logical_power","I51";
;
HDL_POWER"P5V_AUX"
CDS_LIB"logical_power";
"A"7;
%"Q_LED"
"1","(-1125,5750)","2","pure_quanta","I52";
;
PART_NUMBER"BEBL0172Z00"
COLOR"LED_BLUE"
MANUF_PN"LTST-C281TBKT-5A"
PACK_TYPE"SMLF"
MATERIAL"IC"
LOCATION"D97"
CDS_LIB"pure_quanta"
NEEDS_NO_SIZE"TRUE"
$SEC"1"
CDS_SEC"1";
"A"
$PN"A"19;
"C"
$PN"C"16;
%"Q_LED"
"1","(-1100,4625)","2","pure_quanta","I53";
;
PART_NUMBER"BEBL0172Z00"
COLOR"LED_BLUE"
PACK_TYPE"SMLF"
MATERIAL"IC"
MANUF_PN"LTST-C281TBKT-5A"
LOCATION"D98"
NEEDS_NO_SIZE"TRUE"
CDS_LIB"pure_quanta"
$SEC"1"
CDS_SEC"1";
"A"
$PN"A"20;
"C"
$PN"C"17;
%"UNIVERSAL_POWER"
"1","(400,4875)","0","logical_power","I54";
;
HDL_POWER"P5V"
CDS_LIB"logical_power";
"A"6;
%"UNIVERSAL_GND"
"1","(-1700,4375)","0","logical_power","I56";
;
HDL_POWER"GND"
CDS_LIB"logical_power";
"A"17;
%"UNIVERSAL_GND"
"1","(-1775,3150)","0","logical_power","I57";
;
CDS_LIB"logical_power"
HDL_POWER"GND";
"A"18;
%"UNIVERSAL_POWER"
"1","(450,3625)","0","logical_power","I59";
;
HDL_POWER"P3V3"
CDS_LIB"logical_power";
"A"9;
%"MOSFET_NCH_DUAL"
"1","(-5825,5625)","0","pure_quanta","I6";
;
PART_NUMBER"BAM138K0003"
PART_TYPE"SMLF"
VALUE"PJT138K"
MATERIAL"IC"
LOCATION"Q77"
NEEDS_NO_SIZE"TRUE"
CDS_LMAN_SYM_OUTLINE"-150,150,150,-150"
CDS_LIB"pure_quanta"
$SEC"1"
CDS_SEC"1";
"D1"
$PN"6"25;
"G1"
$PN"2"29;
"S1"
$PN"1"14;
%"Q_LED"
"1","(-1175,3400)","2","pure_quanta","I60";
;
PART_NUMBER"BEBL0172Z00"
COLOR"LED_BLUE"
PACK_TYPE"SMLF"
MATERIAL"IC"
MANUF_PN"LTST-C281TBKT-5A"
LOCATION"D99"
CDS_LIB"pure_quanta"
NEEDS_NO_SIZE"TRUE"
$SEC"1"
CDS_SEC"1";
"A"
$PN"A"39;
"C"
$PN"C"18;
%"Q_RES"
"1","(0,4625)","0","pure_quanta","I61";
;
PART_NUMBER"CS14702FB04"
MATERIAL"CHIP"
WATTAGE"1/16W"
VALUE"470"
TOLERANCE"1%"
PACK_TYPE"0402LF"
$LOCATION"R3102"
CDS_LIB"pure_quanta"
CDS_LOCATION"R3102"
$SEC"1"
CDS_SEC"1";
"B"
$PN"2"6;
"A"
$PN"1"20;
%"Q_RES"
"1","(-25,5750)","0","pure_quanta","I62";
;
PART_NUMBER"CS14702FB04"
MATERIAL"CHIP"
WATTAGE"1/16W"
VALUE"470"
TOLERANCE"1%"
PACK_TYPE"0402LF"
$LOCATION"R3101"
CDS_LIB"pure_quanta"
CDS_LOCATION"R3101"
$SEC"1"
CDS_SEC"1";
"B"
$PN"2"7;
"A"
$PN"1"19;
%"Q_RES"
"1","(-75,3400)","0","pure_quanta","I64";
;
PART_NUMBER"CS11302FB03"
WATTAGE"1/16W"
VALUE"130"
TOLERANCE"1%"
MATERIAL"CHIP"
PACK_TYPE"0402LF"
LOCATION"R3100"
CDS_LIB"pure_quanta"
$SEC"1"
CDS_SEC"1";
"B"
$PN"2"9;
"A"
$PN"1"39;
%"MOSFET_NCH_DUAL"
"2","(-5825,6850)","0","pure_quanta","I8";
;
PART_NUMBER"BAM138K0003"
MATERIAL"IC"
PART_TYPE"SMLF"
VALUE"PJT138K"
LOCATION"Q76"
SEC_TYPE""
CDS_LIB"pure_quanta"
NEEDS_NO_SIZE"TRUE"
CDS_LMAN_SYM_OUTLINE"-150,150,150,-150"
SEC"2";
"S2"
$PN"4"13;
"G2"
$PN"5"27;
"D2"
$PN"3"26;
%"UNIVERSAL_GND"
"1","(-5775,6500)","0","logical_power","I9";
;
HDL_POWER"GND"
CDS_LIB"logical_power";
"A"13;
END.
